(kicad_pcb
	(version 20260206)
	(generator "pcbnew")
	(generator_version "10.0")
	(general
		(thickness 1.6)
		(legacy_teardrops no)
	)
	(paper "A4")
	(title_block
		(title "12092022_DA0F0TMDCD0_F0T_Management_Board_D_brd_V3_OCP.brd")
		(comment 1 "Grand Teton / footprints 1297-1301 of 1440")
	)
	(layers
		(0 "F.Cu" signal "TOP")
		(4 "In1.Cu" signal "GND")
		(6 "In2.Cu" signal "IN1")
		(8 "In3.Cu" signal "GND1")
		(10 "In4.Cu" signal "IN2")
		(12 "In5.Cu" signal "VCC")
		(14 "In6.Cu" signal "VCC1")
		(16 "In7.Cu" signal "IN3")
		(18 "In8.Cu" signal "GND2")
		(20 "In9.Cu" signal "IN4")
		(22 "In10.Cu" signal "GND3")
		(2 "B.Cu" signal "BOTTOM")
		(9 "F.Adhes" user "F.Adhesive")
		(11 "B.Adhes" user "B.Adhesive")
		(13 "F.Paste" user "Package Geometry/Pastemask Top")
		(15 "B.Paste" user "Package Geometry/Pastemask Bottom")
		(5 "F.SilkS" user "Ref Des/Silkscreen Top")
		(7 "B.SilkS" user "Ref Des/Silkscreen Bottom")
		(1 "F.Mask" user "Board Geometry/Soldermask Top")
		(3 "B.Mask" user "Board Geometry/Soldermask Bottom")
		(17 "Dwgs.User" user "User.Drawings")
		(19 "Cmts.User" user "User.Comments")
		(21 "Eco1.User" user "User.Eco1")
		(23 "Eco2.User" user "User.Eco2")
		(25 "Edge.Cuts" user "Board Geometry/Outline")
		(27 "Margin" user)
		(31 "F.CrtYd" user "Package Geometry/Place Bound Top")
		(29 "B.CrtYd" user "Package Geometry/Place Bound Bottom")
		(35 "F.Fab" user "Ref Des/Assembly Top")
		(33 "B.Fab" user "Ref Des/Assembly Bottom")
	)
	(footprint ""
		(layer "B.Cu")
		(at 51.2445 -89.5985 180)
		(property "Reference" "R720"
			(at 0 0 0)
			(layer "B.SilkS")
			(hide yes)
			(effects
				(font
					(size 1.27 1.27)
				)
				(justify mirror)
			)
		)
		(property "Value" ""
			(at 0 0 0)
			(layer "B.Fab")
			(effects
				(font
					(size 1.27 1.27)
				)
				(justify mirror)
			)
		)
		(duplicate_pad_numbers_are_jumpers no)
		(fp_line
			(start 0.7874 0.4064)
			(end 0.7874 -0.4064)
			(stroke
				(width 0.1524)
				(type default)
			)
			(layer "B.SilkS")
		)
		(fp_line
			(start 0.7874 -0.4064)
			(end -0.7874 -0.4064)
			(stroke
				(width 0.1524)
				(type default)
			)
			(layer "B.SilkS")
		)
		(fp_line
			(start -0.7874 0.4064)
			(end 0.7874 0.4064)
			(stroke
				(width 0.1524)
				(type default)
			)
			(layer "B.SilkS")
		)
		(fp_line
			(start -0.7874 -0.4064)
			(end -0.7874 0.4064)
			(stroke
				(width 0.1524)
				(type default)
			)
			(layer "B.SilkS")
		)
		(fp_line
			(start 0.67945 0.3048)
			(end 0.67945 -0.305054)
			(stroke
				(width 0.1)
				(type default)
			)
			(layer "B.Fab")
		)
		(fp_line
			(start 0.67945 -0.305054)
			(end 0.12065 -0.305054)
			(stroke
				(width 0.1)
				(type default)
			)
			(layer "B.Fab")
		)
		(fp_line
			(start 0.12065 0.3048)
			(end 0.67945 0.3048)
			(stroke
				(width 0.1)
				(type default)
			)
			(layer "B.Fab")
		)
		(fp_line
			(start 0.12065 0.2794)
			(end 0.12065 0.3048)
			(stroke
				(width 0.1)
				(type default)
			)
			(layer "B.Fab")
		)
		(fp_line
			(start 0.12065 -0.2794)
			(end -0.12065 -0.2794)
			(stroke
				(width 0.1)
				(type default)
			)
			(layer "B.Fab")
		)
		(fp_line
			(start 0.12065 -0.305054)
			(end 0.12065 -0.2794)
			(stroke
				(width 0.1)
				(type default)
			)
			(layer "B.Fab")
		)
		(fp_line
			(start -0.120396 0.3048)
			(end -0.120396 0.2794)
			(stroke
				(width 0.1)
				(type default)
			)
			(layer "B.Fab")
		)
		(fp_line
			(start -0.120396 0.2794)
			(end 0.12065 0.2794)
			(stroke
				(width 0.1)
				(type default)
			)
			(layer "B.Fab")
		)
		(fp_line
			(start -0.12065 -0.2794)
			(end -0.12065 -0.3048)
			(stroke
				(width 0.1)
				(type default)
			)
			(layer "B.Fab")
		)
		(fp_line
			(start -0.12065 -0.3048)
			(end -0.67945 -0.3048)
			(stroke
				(width 0.1)
				(type default)
			)
			(layer "B.Fab")
		)
		(fp_line
			(start -0.67945 0.3048)
			(end -0.120396 0.3048)
			(stroke
				(width 0.1)
				(type default)
			)
			(layer "B.Fab")
		)
		(fp_line
			(start -0.67945 -0.3048)
			(end -0.67945 0.3048)
			(stroke
				(width 0.1)
				(type default)
			)
			(layer "B.Fab")
		)
		(pad "1" smd circle
			(at 0.40005 0)
			(size 0 0)
			(layers "B.Cu" "B.Mask" "B.Paste")
			(net "FM_CPU_MSMI_CATERR_LVT3_N")
		)
		(pad "2" smd circle
			(at -0.40005 0)
			(size 0 0)
			(layers "B.Cu" "B.Mask" "B.Paste")
			(net "FM_CPU_MSMI_CATERR_LVT3_R3_N")
		)
	)
	(footprint ""
		(layer "B.Cu")
		(at 25.459436 -89.18702 180)
		(property "Reference" "C261"
			(at 0 0 0)
			(layer "B.SilkS")
			(hide yes)
			(effects
				(font
					(size 1.27 1.27)
				)
				(justify mirror)
			)
		)
		(property "Value" ""
			(at 0 0 0)
			(layer "B.Fab")
			(effects
				(font
					(size 1.27 1.27)
				)
				(justify mirror)
			)
		)
		(duplicate_pad_numbers_are_jumpers no)
		(fp_line
			(start 0.69215 0.2921)
			(end 0.69215 -0.2921)
			(stroke
				(width 0.1524)
				(type default)
			)
			(layer "B.SilkS")
		)
		(fp_line
			(start 0.69215 -0.2921)
			(end -0.69215 -0.2921)
			(stroke
				(width 0.1524)
				(type default)
			)
			(layer "B.SilkS")
		)
		(fp_line
			(start -0.69215 0.2921)
			(end 0.69215 0.2921)
			(stroke
				(width 0.1524)
				(type default)
			)
			(layer "B.SilkS")
		)
		(fp_line
			(start -0.69215 -0.2921)
			(end -0.69215 0.2921)
			(stroke
				(width 0.1524)
				(type default)
			)
			(layer "B.SilkS")
		)
		(fp_line
			(start 0.51435 0.2794)
			(end 0.51435 -0.2794)
			(stroke
				(width 0.1)
				(type default)
			)
			(layer "B.Fab")
		)
		(fp_line
			(start 0.51435 -0.2794)
			(end -0.51435 -0.2794)
			(stroke
				(width 0.1)
				(type default)
			)
			(layer "B.Fab")
		)
		(fp_line
			(start -0.51435 0.2794)
			(end 0.51435 0.2794)
			(stroke
				(width 0.1)
				(type default)
			)
			(layer "B.Fab")
		)
		(fp_line
			(start -0.51435 -0.2794)
			(end -0.51435 0.2794)
			(stroke
				(width 0.1)
				(type default)
			)
			(layer "B.Fab")
		)
		(pad "1" smd circle
			(at 0.40005 0)
			(size 0 0)
			(layers "B.Cu" "B.Mask" "B.Paste")
			(net "VCCIO0")
		)
		(pad "2" smd circle
			(at -0.40005 0)
			(size 0 0)
			(layers "B.Cu" "B.Mask" "B.Paste")
			(net "GND")
		)
		(zone
			(layer "B.Cu")
			(hatch none 0.5)
			(connect_pads
				(clearance 0)
			)
			(min_thickness 0.25)
			(keepout
				(tracks not_allowed)
				(vias allowed)
				(pads allowed)
				(copperpour not_allowed)
				(footprints allowed)
			)
			(placement
				(enabled no)
				(sheetname "")
			)
			(fill
				(thermal_gap 0.5)
				(thermal_bridge_width 0.5)
				(island_removal_mode 0)
			)
			(polygon
				(pts
					(xy 25.268936 -89.27465) (xy 25.360376 -89.332816) (xy 25.559766 -89.332816) (xy 25.649936 -89.27465)
					(xy 25.649936 -89.09939) (xy 25.559766 -89.04097) (xy 25.360376 -89.04097) (xy 25.268936 -89.099136)
				)
			)
		)
	)
	(footprint ""
		(layer "B.Cu")
		(at 61.57722 -61.985906 -90)
		(property "Reference" "C25"
			(at 0 0 90)
			(layer "B.SilkS")
			(hide yes)
			(effects
				(font
					(size 1.27 1.27)
				)
				(justify mirror)
			)
		)
		(property "Value" ""
			(at 0 0 90)
			(layer "B.Fab")
			(effects
				(font
					(size 1.27 1.27)
				)
				(justify mirror)
			)
		)
		(duplicate_pad_numbers_are_jumpers no)
		(fp_line
			(start -0.7874 0.4064)
			(end 0.7874 0.4064)
			(stroke
				(width 0.1524)
				(type default)
			)
			(layer "B.SilkS")
		)
		(fp_line
			(start 0.7874 0.4064)
			(end 0.7874 -0.10414)
			(stroke
				(width 0.1524)
				(type default)
			)
			(layer "B.SilkS")
		)
		(fp_line
			(start -0.7874 -0.15494)
			(end -0.7874 0.4064)
			(stroke
				(width 0.1524)
				(type default)
			)
			(layer "B.SilkS")
		)
		(fp_line
			(start 0.489966 -0.4064)
			(end -0.480314 -0.4064)
			(stroke
				(width 0.1524)
				(type default)
			)
			(layer "B.SilkS")
		)
		(fp_line
			(start -0.67945 0.3048)
			(end -0.120396 0.3048)
			(stroke
				(width 0.1)
				(type default)
			)
			(layer "B.Fab")
		)
		(fp_line
			(start -0.120396 0.3048)
			(end -0.120396 0.2794)
			(stroke
				(width 0.1)
				(type default)
			)
			(layer "B.Fab")
		)
		(fp_line
			(start 0.12065 0.3048)
			(end 0.67945 0.3048)
			(stroke
				(width 0.1)
				(type default)
			)
			(layer "B.Fab")
		)
		(fp_line
			(start 0.67945 0.3048)
			(end 0.67945 -0.305054)
			(stroke
				(width 0.1)
				(type default)
			)
			(layer "B.Fab")
		)
		(fp_line
			(start -0.120396 0.2794)
			(end 0.12065 0.2794)
			(stroke
				(width 0.1)
				(type default)
			)
			(layer "B.Fab")
		)
		(fp_line
			(start 0.12065 0.2794)
			(end 0.12065 0.3048)
			(stroke
				(width 0.1)
				(type default)
			)
			(layer "B.Fab")
		)
		(fp_line
			(start -0.12065 -0.2794)
			(end -0.12065 -0.3048)
			(stroke
				(width 0.1)
				(type default)
			)
			(layer "B.Fab")
		)
		(fp_line
			(start 0.12065 -0.2794)
			(end -0.12065 -0.2794)
			(stroke
				(width 0.1)
				(type default)
			)
			(layer "B.Fab")
		)
		(fp_line
			(start -0.67945 -0.3048)
			(end -0.67945 0.3048)
			(stroke
				(width 0.1)
				(type default)
			)
			(layer "B.Fab")
		)
		(fp_line
			(start -0.12065 -0.3048)
			(end -0.67945 -0.3048)
			(stroke
				(width 0.1)
				(type default)
			)
			(layer "B.Fab")
		)
		(fp_line
			(start 0.12065 -0.305054)
			(end 0.12065 -0.2794)
			(stroke
				(width 0.1)
				(type default)
			)
			(layer "B.Fab")
		)
		(fp_line
			(start 0.67945 -0.305054)
			(end 0.12065 -0.305054)
			(stroke
				(width 0.1)
				(type default)
			)
			(layer "B.Fab")
		)
		(pad "1" smd circle
			(at 0.40005 0 90)
			(size 0 0)
			(layers "B.Cu" "B.Mask" "B.Paste")
			(net "P2E_PCH_TX_DN")
		)
		(pad "2" smd circle
			(at -0.40005 0 90)
			(size 0 0)
			(layers "B.Cu" "B.Mask" "B.Paste")
			(net "P2E_PCH_TX_C_DN")
		)
	)
	(footprint ""
		(layer "B.Cu")
		(at 30.988 -67.437 -90)
		(property "Reference" "U7"
			(at 1.0922 1.77927 270)
			(unlocked yes)
			(layer "B.SilkS")
			(effects
				(font
					(size 0.7874 0.5842)
					(thickness 0.1524)
				)
				(justify mirror)
			)
		)
		(property "Value" ""
			(at 0 0 90)
			(layer "B.Fab")
			(effects
				(font
					(size 1.27 1.27)
				)
				(justify mirror)
			)
		)
		(duplicate_pad_numbers_are_jumpers no)
		(fp_line
			(start -1.7272 1.1176)
			(end 1.7272 1.1176)
			(stroke
				(width 0.1524)
				(type default)
			)
			(layer "B.SilkS")
		)
		(fp_line
			(start 1.7272 1.1176)
			(end 1.7272 -1.1176)
			(stroke
				(width 0.1524)
				(type default)
			)
			(layer "B.SilkS")
		)
		(fp_line
			(start 0 -0.7366)
			(end 0.254 -1.1176)
			(stroke
				(width 0.1524)
				(type default)
			)
			(layer "B.SilkS")
		)
		(fp_line
			(start -1.7272 -1.1176)
			(end -1.7272 1.1176)
			(stroke
				(width 0.1524)
				(type default)
			)
			(layer "B.SilkS")
		)
		(fp_line
			(start -1.7272 -1.1176)
			(end -0.254 -1.1176)
			(stroke
				(width 0.1524)
				(type default)
			)
			(layer "B.SilkS")
		)
		(fp_line
			(start -0.254 -1.1176)
			(end 0 -0.7366)
			(stroke
				(width 0.1524)
				(type default)
			)
			(layer "B.SilkS")
		)
		(fp_line
			(start 0.254 -1.1176)
			(end 1.7272 -1.1176)
			(stroke
				(width 0.1524)
				(type default)
			)
			(layer "B.SilkS")
		)
		(fp_poly
			(pts
				(xy 2.9718 -0.395986) (xy 3.7338 -0.014986) (xy 3.7338 -0.776986)
			)
			(stroke
				(width 0)
				(type default)
			)
			(fill yes)
			(layer "B.SilkS")
		)
		(fp_line
			(start -1.5748 1.1176)
			(end -1.5748 -1.1176)
			(stroke
				(width 0.1)
				(type default)
			)
			(layer "B.Fab")
		)
		(fp_line
			(start 1.5748 1.1176)
			(end -1.5748 1.1176)
			(stroke
				(width 0.1)
				(type default)
			)
			(layer "B.Fab")
		)
		(fp_line
			(start -1.5748 -1.1176)
			(end 1.5748 -1.1176)
			(stroke
				(width 0.1)
				(type default)
			)
			(layer "B.Fab")
		)
		(fp_line
			(start 1.5748 -1.1176)
			(end 1.5748 1.1176)
			(stroke
				(width 0.1)
				(type default)
			)
			(layer "B.Fab")
		)
		(fp_poly
			(pts
				(xy 1.9558 -0.649986) (xy 2.7178 -0.268986) (xy 2.7178 -1.030986)
			)
			(stroke
				(width 0)
				(type default)
			)
			(fill yes)
			(layer "B.Fab")
		)
		(pad "1" smd rect
			(at 0.999998 -0.649986 180)
			(size 0.3556 1.1176)
			(layers "B.Cu" "B.Mask" "B.Paste")
			(net "SPA_SOUT_SW_DBG_R")
		)
		(pad "2" smd rect
			(at 0.999998 0 180)
			(size 0.3556 1.1176)
			(layers "B.Cu" "B.Mask" "B.Paste")
			(net "GND")
		)
		(pad "3" smd rect
			(at 0.999998 0.649986 180)
			(size 0.3556 1.1176)
			(layers "B.Cu" "B.Mask" "B.Paste")
			(net "UART_SYS_DBG_TX_R")
		)
		(pad "4" smd rect
			(at -0.999998 0.649986 180)
			(size 0.3556 1.1176)
			(layers "B.Cu" "B.Mask" "B.Paste")
			(net "SPA_SOUT_SW_BUF_R")
		)
		(pad "5" smd rect
			(at -0.999998 0 180)
			(size 0.3556 1.1176)
			(layers "B.Cu" "B.Mask" "B.Paste")
			(net "P3V3_AUX")
		)
		(pad "6" smd rect
			(at -0.999998 -0.649986 180)
			(size 0.3556 1.1176)
			(layers "B.Cu" "B.Mask" "B.Paste")
			(net "FM_DBG_SW_N")
		)
	)
	(footprint ""
		(layer "B.Cu")
		(at 56.727852 -30.867604 -90)
		(property "Reference" "R259"
			(at 0 0 90)
			(layer "B.SilkS")
			(hide yes)
			(effects
				(font
					(size 1.27 1.27)
				)
				(justify mirror)
			)
		)
		(property "Value" ""
			(at 0 0 90)
			(layer "B.Fab")
			(effects
				(font
					(size 1.27 1.27)
				)
				(justify mirror)
			)
		)
		(duplicate_pad_numbers_are_jumpers no)
		(fp_line
			(start -0.7874 0.4064)
			(end 0.7874 0.4064)
			(stroke
				(width 0.1524)
				(type default)
			)
			(layer "B.SilkS")
		)
		(fp_line
			(start 0.7874 0.4064)
			(end 0.7874 -0.4064)
			(stroke
				(width 0.1524)
				(type default)
			)
			(layer "B.SilkS")
		)
		(fp_line
			(start -0.7874 -0.4064)
			(end -0.7874 0.4064)
			(stroke
				(width 0.1524)
				(type default)
			)
			(layer "B.SilkS")
		)
		(fp_line
			(start 0.7874 -0.4064)
			(end -0.7874 -0.4064)
			(stroke
				(width 0.1524)
				(type default)
			)
			(layer "B.SilkS")
		)
		(fp_line
			(start -0.67945 0.3048)
			(end -0.120396 0.3048)
			(stroke
				(width 0.1)
				(type default)
			)
			(layer "B.Fab")
		)
		(fp_line
			(start -0.120396 0.3048)
			(end -0.120396 0.2794)
			(stroke
				(width 0.1)
				(type default)
			)
			(layer "B.Fab")
		)
		(fp_line
			(start 0.12065 0.3048)
			(end 0.67945 0.3048)
			(stroke
				(width 0.1)
				(type default)
			)
			(layer "B.Fab")
		)
		(fp_line
			(start 0.67945 0.3048)
			(end 0.67945 -0.305054)
			(stroke
				(width 0.1)
				(type default)
			)
			(layer "B.Fab")
		)
		(fp_line
			(start -0.120396 0.2794)
			(end 0.12065 0.2794)
			(stroke
				(width 0.1)
				(type default)
			)
			(layer "B.Fab")
		)
		(fp_line
			(start 0.12065 0.2794)
			(end 0.12065 0.3048)
			(stroke
				(width 0.1)
				(type default)
			)
			(layer "B.Fab")
		)
		(fp_line
			(start -0.12065 -0.2794)
			(end -0.12065 -0.3048)
			(stroke
				(width 0.1)
				(type default)
			)
			(layer "B.Fab")
		)
		(fp_line
			(start 0.12065 -0.2794)
			(end -0.12065 -0.2794)
			(stroke
				(width 0.1)
				(type default)
			)
			(layer "B.Fab")
		)
		(fp_line
			(start -0.67945 -0.3048)
			(end -0.67945 0.3048)
			(stroke
				(width 0.1)
				(type default)
			)
			(layer "B.Fab")
		)
		(fp_line
			(start -0.12065 -0.3048)
			(end -0.67945 -0.3048)
			(stroke
				(width 0.1)
				(type default)
			)
			(layer "B.Fab")
		)
		(fp_line
			(start 0.12065 -0.305054)
			(end 0.12065 -0.2794)
			(stroke
				(width 0.1)
				(type default)
			)
			(layer "B.Fab")
		)
		(fp_line
			(start 0.67945 -0.305054)
			(end 0.12065 -0.305054)
			(stroke
				(width 0.1)
				(type default)
			)
			(layer "B.Fab")
		)
		(pad "1" smd circle
			(at 0.40005 0 90)
			(size 0 0)
			(layers "B.Cu" "B.Mask" "B.Paste")
			(net "P3V3_AUX")
		)
		(pad "2" smd circle
			(at -0.40005 0 90)
			(size 0 0)
			(layers "B.Cu" "B.Mask" "B.Paste")
			(net "SMB_BMC_MM8_SDA")
		)
	)
)
